# BASEBOARD_FAB2 (Tioga Pass) — schematic netlist excerpt (pin names and nets, part order shuffled) for the footprints in the layout excerpt that follows; sources: Cadence DE-HDL packaged netlist, KiCad conversion of Wiwynn_Tioga_Pass_MB.brd

R25W7  120R2F-GP  1%  pkg RCL_GP  page 151 : \1\ = GND ; \2\ = BMC_M_CAS_N
C25W2  CAP  1.0UF 16V 10% X6S  pkg 0402  page 151 : A = P1V2_AUX_BMC ; B = GND
C5G5  CAP_A  47UF 4V 20% X5R  pkg 0603V  page 217 : A = PVDDQ_ABC ; B = GND

(kicad_pcb
	(version 20260206)
	(generator "pcbnew")
	(generator_version "10.0")
	(general
		(thickness 1.6)
		(legacy_teardrops no)
	)
	(paper "A4")
	(title_block
		(title "Wiwynn_Tioga_Pass_MB.brd")
		(comment 1 "Tioga Pass / footprints 637-639 of 4770")
	)
	(layers
		(0 "F.Cu" signal "TOP")
		(4 "In1.Cu" signal "L2GND")
		(6 "In2.Cu" signal "L3")
		(8 "In3.Cu" signal "L4GND")
		(10 "In4.Cu" signal "L5")
		(12 "In5.Cu" signal "L6GND")
		(14 "In6.Cu" signal "L7VCC")
		(16 "In7.Cu" signal "L8VCC")
		(18 "In8.Cu" signal "L9GND")
		(20 "In9.Cu" signal "L10")
		(22 "In10.Cu" signal "L11GND")
		(24 "In11.Cu" signal "L12")
		(26 "In12.Cu" signal "L13GND")
		(2 "B.Cu" signal "BOTTOM")
		(9 "F.Adhes" user "F.Adhesive")
		(11 "B.Adhes" user "B.Adhesive")
		(13 "F.Paste" user "Package Geometry/Pastemask Top")
		(15 "B.Paste" user "Package Geometry/Pastemask Bottom")
		(5 "F.SilkS" user "Ref Des/Silkscreen Top")
		(7 "B.SilkS" user "Ref Des/Silkscreen Bottom")
		(1 "F.Mask" user "Board Geometry/Soldermask Top")
		(3 "B.Mask" user "Board Geometry/Soldermask Bottom")
		(17 "Dwgs.User" user "User.Drawings")
		(19 "Cmts.User" user "User.Comments")
		(21 "Eco1.User" user "User.Eco1")
		(23 "Eco2.User" user "User.Eco2")
		(25 "Edge.Cuts" user "Board Geometry/Outline")
		(27 "Margin" user)
		(31 "F.CrtYd" user "Package Geometry/Place Bound Top")
		(29 "B.CrtYd" user "Package Geometry/Place Bound Bottom")
		(35 "F.Fab" user "Ref Des/Assembly Top")
		(33 "B.Fab" user "Ref Des/Assembly Bottom")
	)
	(footprint ""
		(layer "F.Cu")
		(at 439.976006 -41.663874 180)
		(property "Reference" "R25W7"
			(at 0 0 180)
			(layer "F.SilkS")
			(hide yes)
			(effects
				(font
					(size 1.27 1.27)
				)
			)
		)
		(property "Value" "*"
			(at 0.064008 -4.108196 180)
			(unlocked yes)
			(layer "F.Fab")
			(hide yes)
			(effects
				(font
					(size 1.27 1.016)
					(thickness 0.1524)
				)
			)
		)
		(property "Device Type" "120R2F-GP_RCL_GP-120R2F-GP,64.A"
			(at 0.064008 -5.632196 180)
			(unlocked yes)
			(layer "F.Fab")
			(hide yes)
			(effects
				(font
					(size 1.27 1.016)
					(thickness 0.1524)
				)
			)
		)
		(duplicate_pad_numbers_are_jumpers no)
		(fp_line
			(start 0.508 -0.9398)
			(end -0.508 -0.9398)
			(stroke
				(width 0.1524)
				(type default)
			)
			(layer "F.SilkS")
		)
		(fp_line
			(start -0.508 -0.9398)
			(end -0.508 0.9398)
			(stroke
				(width 0.1524)
				(type default)
			)
			(layer "F.SilkS")
		)
		(fp_rect
			(start -0.508 0.9398)
			(end 0.508 -0.9398)
			(stroke
				(width 0)
				(type default)
			)
			(fill no)
			(layer "F.CrtYd")
		)
		(fp_rect
			(start -0.508 0.9398)
			(end 0.508 -0.9398)
			(stroke
				(width 0)
				(type default)
			)
			(fill no)
			(layer "F.Fab")
		)
		(pad "1" smd custom
			(at 0 -0.4445 180)
			(size 0.1397 0.1397)
			(layers "F.Cu" "F.Mask" "F.Paste")
			(net "GND")
			(options
				(clearance outline)
				(anchor circle)
			)
			(primitives
				(gr_poly
					(pts
						(arc
							(start -0.1778 -0.2794)
							(mid -0.249642 -0.249642)
							(end -0.2794 -0.1778)
						)
						(arc
							(start -0.2794 0.1778)
							(mid -0.249642 0.249642)
							(end -0.1778 0.2794)
						)
						(arc
							(start 0.1778 0.2794)
							(mid 0.249642 0.249642)
							(end 0.2794 0.1778)
						)
						(arc
							(start 0.2794 -0.1778)
							(mid 0.249642 -0.249642)
							(end 0.1778 -0.2794)
						)
					)
					(width 0)
					(fill yes)
				)
			)
		)
		(pad "2" smd custom
			(at 0 0.4445 180)
			(size 0.1397 0.1397)
			(layers "F.Cu" "F.Mask" "F.Paste")
			(net "BMC_M_CAS_N")
			(options
				(clearance outline)
				(anchor circle)
			)
			(primitives
				(gr_poly
					(pts
						(arc
							(start -0.1778 -0.2794)
							(mid -0.249642 -0.249642)
							(end -0.2794 -0.1778)
						)
						(arc
							(start -0.2794 0.1778)
							(mid -0.249642 0.249642)
							(end -0.1778 0.2794)
						)
						(arc
							(start 0.1778 0.2794)
							(mid 0.249642 0.249642)
							(end 0.2794 0.1778)
						)
						(arc
							(start 0.2794 -0.1778)
							(mid 0.249642 -0.249642)
							(end 0.1778 -0.2794)
						)
					)
					(width 0)
					(fill yes)
				)
			)
		)
	)
	(footprint ""
		(layer "F.Cu")
		(at 266.397232 -12.954 90)
		(property "Reference" "C5G5"
			(at 1.848866 0.752348 90)
			(unlocked yes)
			(layer "F.SilkS")
			(effects
				(font
					(size 1.27 0.9652)
					(thickness 0.1524)
				)
			)
		)
		(property "Value" ""
			(at 0 0 90)
			(layer "F.Fab")
			(effects
				(font
					(size 1.27 1.27)
				)
			)
		)
		(duplicate_pad_numbers_are_jumpers no)
		(fp_rect
			(start -0.500126 1.598422)
			(end 0.500126 -0.201422)
			(stroke
				(width 0)
				(type default)
			)
			(fill no)
			(layer "F.CrtYd")
		)
		(fp_line
			(start 0.500126 -0.201422)
			(end 0.500126 1.598422)
			(stroke
				(width 0.1)
				(type default)
			)
			(layer "F.Fab")
		)
		(fp_line
			(start -0.500126 -0.201422)
			(end 0.500126 -0.201422)
			(stroke
				(width 0.1)
				(type default)
			)
			(layer "F.Fab")
		)
		(fp_line
			(start 0.500126 1.598422)
			(end -0.500126 1.598422)
			(stroke
				(width 0.1)
				(type default)
			)
			(layer "F.Fab")
		)
		(fp_line
			(start -0.500126 1.598422)
			(end -0.500126 -0.201422)
			(stroke
				(width 0.1)
				(type default)
			)
			(layer "F.Fab")
		)
		(pad "1" smd rect
			(at 0 0)
			(size 0.889 0.9906)
			(layers "F.Cu" "F.Mask" "F.Paste")
			(net "PVDDQ_ABC")
		)
		(pad "2" smd rect
			(at 0 1.397)
			(size 0.889 0.9906)
			(layers "F.Cu" "F.Mask" "F.Paste")
			(net "GND")
		)
		(zone
			(layer "F.Cu")
			(hatch none 0.5)
			(connect_pads
				(clearance 0)
			)
			(min_thickness 0.25)
			(keepout
				(tracks not_allowed)
				(vias allowed)
				(pads allowed)
				(copperpour not_allowed)
				(footprints allowed)
			)
			(placement
				(enabled no)
				(sheetname "")
			)
			(fill
				(thermal_gap 0.5)
				(thermal_bridge_width 0.5)
				(island_removal_mode 0)
			)
			(polygon
				(pts
					(xy 267.349732 -12.4587) (xy 267.349732 -13.4493) (xy 266.841732 -13.4493) (xy 266.841732 -12.4587)
				)
			)
		)
		(zone
			(layer "F.Cu")
			(hatch none 0.5)
			(connect_pads
				(clearance 0)
			)
			(min_thickness 0.25)
			(keepout
				(tracks allowed)
				(vias not_allowed)
				(pads allowed)
				(copperpour not_allowed)
				(footprints allowed)
			)
			(placement
				(enabled no)
				(sheetname "")
			)
			(fill
				(thermal_gap 0.5)
				(thermal_bridge_width 0.5)
				(island_removal_mode 0)
			)
			(polygon
				(pts
					(xy 267.349732 -12.4587) (xy 267.349732 -13.4493) (xy 266.841732 -13.4493) (xy 266.841732 -12.4587)
				)
			)
		)
	)
	(footprint ""
		(layer "F.Cu")
		(at 451.358 -28.7655)
		(property "Reference" "C25W2"
			(at -0.8382 -0.67818 0)
			(unlocked yes)
			(layer "F.SilkS")
			(effects
				(font
					(size 0.4064 0.254)
					(thickness 0.1524)
				)
				(justify left)
			)
		)
		(property "Value" ""
			(at 0 0 0)
			(layer "F.Fab")
			(effects
				(font
					(size 1.27 1.27)
				)
			)
		)
		(duplicate_pad_numbers_are_jumpers no)
		(fp_poly
			(pts
				(xy 0.3048 -0.1016) (xy 0.3048 0.9906) (xy -0.3048 0.9906) (xy -0.3048 -0.1016)
			)
			(stroke
				(width 0)
				(type default)
			)
			(fill no)
			(layer "F.CrtYd")
		)
		(fp_line
			(start -0.3048 -0.1016)
			(end -0.3048 0.9906)
			(stroke
				(width 0.1)
				(type default)
			)
			(layer "F.Fab")
		)
		(fp_line
			(start -0.3048 0.9906)
			(end 0.3048 0.9906)
			(stroke
				(width 0.1)
				(type default)
			)
			(layer "F.Fab")
		)
		(fp_line
			(start 0.3048 -0.1016)
			(end -0.3048 -0.1016)
			(stroke
				(width 0.1)
				(type default)
			)
			(layer "F.Fab")
		)
		(fp_line
			(start 0.3048 0.9906)
			(end 0.3048 -0.1016)
			(stroke
				(width 0.1)
				(type default)
			)
			(layer "F.Fab")
		)
		(pad "1" smd rect
			(at 0 0)
			(size 0.508 0.508)
			(layers "F.Cu" "F.Mask" "F.Paste")
			(net "P1V2_AUX_BMC")
		)
		(pad "2" smd rect
			(at 0 0.889)
			(size 0.508 0.508)
			(layers "F.Cu" "F.Mask" "F.Paste")
			(net "GND")
		)
		(zone
			(layer "F.Cu")
			(hatch none 0.5)
			(connect_pads
				(clearance 0)
			)
			(min_thickness 0.25)
			(keepout
				(tracks allowed)
				(vias not_allowed)
				(pads allowed)
				(copperpour not_allowed)
				(footprints allowed)
			)
			(placement
				(enabled no)
				(sheetname "")
			)
			(fill
				(thermal_gap 0.5)
				(thermal_bridge_width 0.5)
				(island_removal_mode 0)
			)
			(polygon
				(pts
					(xy 451.104 -28.5115) (xy 451.612 -28.5115) (xy 451.612 -28.1305) (xy 451.104 -28.1305)
				)
			)
		)
		(zone
			(layer "F.Cu")
			(hatch none 0.5)
			(connect_pads
				(clearance 0)
			)
			(min_thickness 0.25)
			(keepout
				(tracks not_allowed)
				(vias allowed)
				(pads allowed)
				(copperpour not_allowed)
				(footprints allowed)
			)
			(placement
				(enabled no)
				(sheetname "")
			)
			(fill
				(thermal_gap 0.5)
				(thermal_bridge_width 0.5)
				(island_removal_mode 0)
			)
			(polygon
				(pts
					(xy 451.104 -28.1305) (xy 451.612 -28.1305) (xy 451.612 -28.5115) (xy 451.104 -28.5115)
				)
			)
		)
	)
)
